FILE_TYPE=LIBRARY_PARTS;
primitive 'MOSFET_DUAL_6P';
  pin
    'G1':
      PIN_NUMBER='(2)';
      BIDIRECTIONAL='TRUE';
      INPUT_LOAD='(-0.01,0.01)';
      OUTPUT_LOAD='(1.0,-1.0)';
    'G2':
      PIN_NUMBER='(5)';
      BIDIRECTIONAL='TRUE';
      INPUT_LOAD='(-0.01,0.01)';
      OUTPUT_LOAD='(1.0,-1.0)';
    'S1':
      PIN_NUMBER='(1)';
      BIDIRECTIONAL='TRUE';
      INPUT_LOAD='(-0.01,0.01)';
      OUTPUT_LOAD='(1.0,-1.0)';
    'S2':
      PIN_NUMBER='(4)';
      BIDIRECTIONAL='TRUE';
      INPUT_LOAD='(-0.01,0.01)';
      OUTPUT_LOAD='(1.0,-1.0)';
    'D1':
      PIN_NUMBER='(6)';
      BIDIRECTIONAL='TRUE';
      INPUT_LOAD='(-0.01,0.01)';
      OUTPUT_LOAD='(1.0,-1.0)';
    'D2':
      PIN_NUMBER='(3)';
      BIDIRECTIONAL='TRUE';
      INPUT_LOAD='(-0.01,0.01)';
      OUTPUT_LOAD='(1.0,-1.0)';
  end_pin;
  body
    PART_NAME='MOSFET_DUAL_6P';
    BODY_NAME='MOSFET_DUAL_6P';
    PHYS_DES_PREFIX='Q';
    CLASS='DISCRETE';
  end_body;
end_primitive;

END.
